(kicad_pcb
	(version 20221018)
	(generator pcbnew)
	(general
    (thickness 1.518)
  )
	(paper "A4")
	(title_block
    (title "Kria K26 Devboard")
    (date "2024-03-26")
    (rev "1.2.5")
    (comment 1 "www.antmicro.com")
    (comment 2 "Antmicro Ltd.")
		(comment 9 "footprints 545-554 of 660")
	)
	(layers
    (0 "F.Cu" mixed)
    (1 "In1.Cu" power)
    (2 "In2.Cu" mixed)
    (3 "In3.Cu" power)
    (4 "In4.Cu" mixed)
    (5 "In5.Cu" power)
    (6 "In6.Cu" mixed)
    (31 "B.Cu" power)
    (32 "B.Adhes" user "B.Adhesive")
    (33 "F.Adhes" user "F.Adhesive")
    (34 "B.Paste" user)
    (35 "F.Paste" user)
    (36 "B.SilkS" user "B.Silkscreen")
    (37 "F.SilkS" user "F.Silkscreen")
    (38 "B.Mask" user)
    (39 "F.Mask" user)
    (40 "Dwgs.User" user "User.Drawings")
    (41 "Cmts.User" user "User.Comments")
    (42 "Eco1.User" user "User.Eco1")
    (43 "Eco2.User" user "User.Eco2")
    (44 "Edge.Cuts" user)
    (45 "Margin" user)
    (46 "B.CrtYd" user "B.Courtyard")
    (47 "F.CrtYd" user "F.Courtyard")
    (48 "B.Fab" user)
    (49 "F.Fab" user)
  )
	(footprint "kria-k26-devboard-footprints:C_0402_1005Metric" (layer "B.Cu")
    (at 137.75 65.55)
    (descr "Capacitor SMD 0402")
    (tags "capacitor SMD 0402")
    (property "Author" "Antmicro")
    (property "Dielectric" "")
    (property "License" "Apache-2.0")
    (property "MPN" "CC0402MRX5R5BB106")
    (property "Manufacturer" "Yaego")
    (property "Sheetfile" "usb.kicad_sch")
    (property "Sheetname" "USB")
    (property "Val" "10u")
    (property "Voltage" "")
    (property "ki_description" " ")
    (attr smd)
    (fp_text reference "C71" (at 3.04 0.35 180) (layer "B.SilkS")
        (effects (font (size 0.7 0.7) (thickness 0.15)) (justify left bottom mirror))
    )
    (fp_text value "C_10u_0402" (at 0 -1.4 180) (layer "B.Fab") hide
        (effects (font (size 0.7 0.7) (thickness 0.15)) (justify left bottom mirror))
    )
    (fp_text user "License: Apache-2.0" (at -0.932 -5.17 180) (layer "B.Fab") hide
        (effects (font (size 0.7 0.7) (thickness 0.15)) (justify left bottom mirror))
    )
    (fp_text user "Author: Antmicro" (at -0.932 -4.17 180) (layer "B.Fab") hide
        (effects (font (size 0.7 0.7) (thickness 0.15)) (justify left bottom mirror))
    )
    (fp_text user "${REFERENCE}" (at -0.932 -3.168 180) (layer "B.Fab") hide
        (effects (font (size 0.7 0.7) (thickness 0.15)) (justify left bottom mirror))
    )
    (fp_rect (start -0.94 0.47) (end 0.94 -0.47)
      (stroke (width 0.05) (type solid)) (fill none) (layer "B.CrtYd"))
    (fp_rect (start -0.499 0.249) (end 0.499 -0.249)
      (stroke (width 0.15) (type solid)) (fill none) (layer "B.Fab"))
    (pad "1" smd roundrect (at -0.484 0) (size 0.59 0.64) (layers "B.Cu" "B.Paste" "B.Mask") (roundrect_rratio 0.25)
      (net 85 "/USB/USB2_VBUS") (pintype "passive"))
    (pad "2" smd roundrect (at 0.484 0) (size 0.59 0.64) (layers "B.Cu" "B.Paste" "B.Mask") (roundrect_rratio 0.25)
      (net 1 "GND") (pintype "passive"))
  )
	(footprint "kria-k26-devboard-footprints:R_0402_1005Metric" (layer "B.Cu")
    (at 85.3 122.85 180)
    (descr "Resistor SMD 0402")
    (tags "resistor SMD 0402")
    (property "Author" "Antmicro")
    (property "License" "Apache-2.0")
    (property "MPN" "CR0402-FX-2201GLF")
    (property "Manufacturer" "Bourns")
    (property "Sheetfile" "camera.kicad_sch")
    (property "Sheetname" "Camera interface")
    (property "Tolerance" "1%")
    (property "Val" "2k2")
    (property "ki_description" "2k2 resistor in 0402 package with 1% tolerance")
    (attr smd)
    (fp_text reference "R23" (at -3.04 -0.38) (layer "B.SilkS")
        (effects (font (size 0.7 0.7) (thickness 0.15)) (justify left bottom mirror))
    )
    (fp_text value "R_2k2_0402" (at 0 -1.4) (layer "B.Fab") hide
        (effects (font (size 0.7 0.7) (thickness 0.15)) (justify left bottom mirror))
    )
    (fp_text user "License: Apache-2.0" (at -0.95 -5.169) (layer "B.Fab") hide
        (effects (font (size 0.7 0.7) (thickness 0.15)) (justify left bottom mirror))
    )
    (fp_text user "Author: Antmicro" (at -0.95 -4.169) (layer "B.Fab") hide
        (effects (font (size 0.7 0.7) (thickness 0.15)) (justify left bottom mirror))
    )
    (fp_text user "${REFERENCE}" (at -0.95 -3.168) (layer "B.Fab") hide
        (effects (font (size 0.7 0.7) (thickness 0.15)) (justify left bottom mirror))
    )
    (fp_rect (start -0.93 0.47) (end 0.93 -0.47)
      (stroke (width 0.05) (type solid)) (fill none) (layer "B.CrtYd"))
    (fp_rect (start -0.5 0.25) (end 0.5 -0.25)
      (stroke (width 0.15) (type solid)) (fill none) (layer "B.Fab"))
    (pad "1" smd roundrect (at -0.485 0 180) (size 0.59 0.64) (layers "B.Cu" "B.Paste" "B.Mask") (roundrect_rratio 0.25)
      (net 20 "PL_3V3") (pintype "passive"))
    (pad "2" smd roundrect (at 0.485 0 180) (size 0.59 0.64) (layers "B.Cu" "B.Paste" "B.Mask") (roundrect_rratio 0.25)
      (net 225 "/Camera interface/HDA01") (pintype "passive"))
  )
	(footprint "kria-k26-devboard-footprints:C_0402_1005Metric" (layer "B.Cu")
    (at 85.31 121.89)
    (descr "Capacitor SMD 0402")
    (tags "capacitor SMD 0402")
    (property "Author" "Antmicro")
    (property "Dielectric" "X5R")
    (property "License" "Apache-2.0")
    (property "MPN" "GRM155R61H104KE14D")
    (property "Manufacturer" "Murata")
    (property "Sheetfile" "camera.kicad_sch")
    (property "Sheetname" "Camera interface")
    (property "Val" "100n")
    (property "Voltage" "50V")
    (property "ki_description" " ")
    (attr smd)
    (fp_text reference "C29" (at 3.06 0.36 180) (layer "B.SilkS")
        (effects (font (size 0.7 0.7) (thickness 0.15)) (justify left bottom mirror))
    )
    (fp_text value "C_100n_0402" (at 0 -1.4 180) (layer "B.Fab") hide
        (effects (font (size 0.7 0.7) (thickness 0.15)) (justify left bottom mirror))
    )
    (fp_text user "License: Apache-2.0" (at -0.932 -5.17 180) (layer "B.Fab") hide
        (effects (font (size 0.7 0.7) (thickness 0.15)) (justify left bottom mirror))
    )
    (fp_text user "${REFERENCE}" (at -0.932 -3.168 180) (layer "B.Fab") hide
        (effects (font (size 0.7 0.7) (thickness 0.15)) (justify left bottom mirror))
    )
    (fp_text user "Author: Antmicro" (at -0.932 -4.17 180) (layer "B.Fab") hide
        (effects (font (size 0.7 0.7) (thickness 0.15)) (justify left bottom mirror))
    )
    (fp_rect (start -0.94 0.47) (end 0.94 -0.47)
      (stroke (width 0.05) (type solid)) (fill none) (layer "B.CrtYd"))
    (fp_rect (start -0.499 0.249) (end 0.499 -0.249)
      (stroke (width 0.15) (type solid)) (fill none) (layer "B.Fab"))
    (pad "1" smd roundrect (at -0.484 0) (size 0.59 0.64) (layers "B.Cu" "B.Paste" "B.Mask") (roundrect_rratio 0.25)
      (net 20 "PL_3V3") (pintype "passive"))
    (pad "2" smd roundrect (at 0.484 0) (size 0.59 0.64) (layers "B.Cu" "B.Paste" "B.Mask") (roundrect_rratio 0.25)
      (net 1 "GND") (pintype "passive"))
  )
	(footprint "kria-k26-devboard-footprints:C_0402_1005Metric" (layer "B.Cu")
    (at 149.45 85.762385 -90)
    (descr "Capacitor SMD 0402")
    (tags "capacitor SMD 0402")
    (property "Author" "Antmicro")
    (property "Dielectric" "X5R")
    (property "License" "Apache-2.0")
    (property "MPN" "GRM155R61H104KE14D")
    (property "Manufacturer" "Murata")
    (property "Sheetfile" "eth.kicad_sch")
    (property "Sheetname" "Ethernet")
    (property "Val" "100n")
    (property "Voltage" "50V")
    (property "ki_description" " ")
    (attr smd)
    (fp_text reference "C105" (at -3.712385 -0.37 90) (layer "B.SilkS")
        (effects (font (size 0.7 0.7) (thickness 0.15)) (justify left bottom mirror))
    )
    (fp_text value "C_100n_0402" (at 0 -1.4 90) (layer "B.Fab") hide
        (effects (font (size 0.7 0.7) (thickness 0.15)) (justify left bottom mirror))
    )
    (fp_text user "${REFERENCE}" (at -0.932 -3.168 90) (layer "B.Fab") hide
        (effects (font (size 0.7 0.7) (thickness 0.15)) (justify left bottom mirror))
    )
    (fp_text user "Author: Antmicro" (at -0.932 -4.17 90) (layer "B.Fab") hide
        (effects (font (size 0.7 0.7) (thickness 0.15)) (justify left bottom mirror))
    )
    (fp_text user "License: Apache-2.0" (at -0.932 -5.17 90) (layer "B.Fab") hide
        (effects (font (size 0.7 0.7) (thickness 0.15)) (justify left bottom mirror))
    )
    (fp_rect (start -0.94 0.47) (end 0.94 -0.47)
      (stroke (width 0.05) (type solid)) (fill none) (layer "B.CrtYd"))
    (fp_rect (start -0.499 0.249) (end 0.499 -0.249)
      (stroke (width 0.15) (type solid)) (fill none) (layer "B.Fab"))
    (pad "1" smd roundrect (at -0.484 0 270) (size 0.59 0.64) (layers "B.Cu" "B.Paste" "B.Mask") (roundrect_rratio 0.25)
      (net 19 "PS_1V0") (pintype "passive"))
    (pad "2" smd roundrect (at 0.484 0 270) (size 0.59 0.64) (layers "B.Cu" "B.Paste" "B.Mask") (roundrect_rratio 0.25)
      (net 1 "GND") (pintype "passive"))
  )
	(footprint "kria-k26-devboard-footprints:C_0603_1608Metric" (layer "B.Cu")
    (at 155.3 85.4)
    (descr "Capacitor SMD 0603")
    (tags "capacitor 0603")
    (property "Author" "Antmicro")
    (property "License" "Apache-2.0")
    (property "MPN" "GRM188R61A106KE69D")
    (property "Manufacturer" "Murata")
    (property "Sheetfile" "eth.kicad_sch")
    (property "Sheetname" "Ethernet")
    (property "Val" "10u")
    (property "Voltage" "")
    (property "ki_description" " ")
    (attr smd)
    (fp_text reference "C90" (at 3.349 0.44 180) (layer "B.SilkS")
        (effects (font (size 0.7 0.7) (thickness 0.15)) (justify left bottom mirror))
    )
    (fp_text value "C_10u_0603" (at 0 -1.6 180) (layer "B.Fab") hide
        (effects (font (size 0.7 0.7) (thickness 0.15)) (justify left bottom mirror))
    )
    (fp_text user "Author: Antmicro" (at -1.682 -4.894 180) (layer "B.Fab") hide
        (effects (font (size 0.7 0.7) (thickness 0.15)) (justify left bottom mirror))
    )
    (fp_text user "${REFERENCE}" (at -1.682 -3.895 180) (layer "B.Fab") hide
        (effects (font (size 0.7 0.7) (thickness 0.15)) (justify left bottom mirror))
    )
    (fp_text user "License: Apache-2.0" (at -1.682 -5.895 180) (layer "B.Fab") hide
        (effects (font (size 0.7 0.7) (thickness 0.15)) (justify left bottom mirror))
    )
    (fp_line (start -0.3 -0.3) (end 0.3 -0.3)
      (stroke (width 0.15) (type solid)) (layer "B.SilkS"))
    (fp_line (start -0.3 0.3) (end 0.3 0.3)
      (stroke (width 0.15) (type solid)) (layer "B.SilkS"))
    (fp_rect (start -1.24 0.7) (end 1.24 -0.7)
      (stroke (width 0.05) (type solid)) (fill none) (layer "B.CrtYd"))
    (fp_rect (start -0.8 0.4) (end 0.8 -0.4)
      (stroke (width 0.15) (type solid)) (fill none) (layer "B.Fab"))
    (pad "1" smd roundrect (at -0.7 0) (size 0.6 0.8) (layers "B.Cu" "B.Paste" "B.Mask") (roundrect_rratio 0.2)
      (net 17 "PS_1V8") (pintype "passive"))
    (pad "2" smd roundrect (at 0.7 0) (size 0.6 0.8) (layers "B.Cu" "B.Paste" "B.Mask") (roundrect_rratio 0.2)
      (net 1 "GND") (pintype "passive"))
  )
	(footprint "kria-k26-devboard-footprints:R_0402_1005Metric" (layer "B.Cu")
    (at 150.9 93.7)
    (descr "Resistor SMD 0402")
    (tags "resistor SMD 0402")
    (property "Author" "Antmicro")
    (property "License" "Apache-2.0")
    (property "MPN" "CR0402-FX-2491GLF")
    (property "Manufacturer" "Bourns")
    (property "Sheetfile" "eth.kicad_sch")
    (property "Sheetname" "Ethernet")
    (property "Tolerance" "1%")
    (property "Val" "2k49")
    (property "ki_description" "2k49 resistor in 0402 package with 1% tolerance")
    (attr smd)
    (fp_text reference "R68" (at 2.97 0.4 180) (layer "B.SilkS")
        (effects (font (size 0.7 0.7) (thickness 0.15)) (justify left bottom mirror))
    )
    (fp_text value "R_2k49_0402" (at 0 -1.4 180) (layer "B.Fab") hide
        (effects (font (size 0.7 0.7) (thickness 0.15)) (justify left bottom mirror))
    )
    (fp_text user "Author: Antmicro" (at -0.95 -4.169 180) (layer "B.Fab") hide
        (effects (font (size 0.7 0.7) (thickness 0.15)) (justify left bottom mirror))
    )
    (fp_text user "${REFERENCE}" (at -0.95 -3.168 180) (layer "B.Fab") hide
        (effects (font (size 0.7 0.7) (thickness 0.15)) (justify left bottom mirror))
    )
    (fp_text user "License: Apache-2.0" (at -0.95 -5.169 180) (layer "B.Fab") hide
        (effects (font (size 0.7 0.7) (thickness 0.15)) (justify left bottom mirror))
    )
    (fp_rect (start -0.93 0.47) (end 0.93 -0.47)
      (stroke (width 0.05) (type solid)) (fill none) (layer "B.CrtYd"))
    (fp_rect (start -0.5 0.25) (end 0.5 -0.25)
      (stroke (width 0.15) (type solid)) (fill none) (layer "B.Fab"))
    (pad "1" smd roundrect (at -0.485 0) (size 0.59 0.64) (layers "B.Cu" "B.Paste" "B.Mask") (roundrect_rratio 0.25)
      (net 30 "/Ethernet/MIO71") (pintype "passive"))
    (pad "2" smd roundrect (at 0.485 0) (size 0.59 0.64) (layers "B.Cu" "B.Paste" "B.Mask") (roundrect_rratio 0.25)
      (net 1 "GND") (pintype "passive"))
  )
	(footprint "kria-k26-devboard-footprints:R_0402_1005Metric" (layer "B.Cu")
    (at 150.885 92.75 180)
    (descr "Resistor SMD 0402")
    (tags "resistor SMD 0402")
    (property "Author" "Antmicro")
    (property "License" "Apache-2.0")
    (property "MPN" "CR0402-FX-1002GLF")
    (property "Manufacturer" "Bourns")
    (property "Sheetfile" "eth.kicad_sch")
    (property "Sheetname" "Ethernet")
    (property "Tolerance" "1%")
    (property "Val" "10k")
    (property "ki_description" "10k resistor in 0402 package with 1% tolerance")
    (attr smd)
    (fp_text reference "R67" (at -2.965 -0.36) (layer "B.SilkS")
        (effects (font (size 0.7 0.7) (thickness 0.15)) (justify left bottom mirror))
    )
    (fp_text value "R_10k_0402" (at 0 -1.4) (layer "B.Fab") hide
        (effects (font (size 0.7 0.7) (thickness 0.15)) (justify left bottom mirror))
    )
    (fp_text user "License: Apache-2.0" (at -0.95 -5.169) (layer "B.Fab") hide
        (effects (font (size 0.7 0.7) (thickness 0.15)) (justify left bottom mirror))
    )
    (fp_text user "${REFERENCE}" (at -0.95 -3.168) (layer "B.Fab") hide
        (effects (font (size 0.7 0.7) (thickness 0.15)) (justify left bottom mirror))
    )
    (fp_text user "Author: Antmicro" (at -0.95 -4.169) (layer "B.Fab") hide
        (effects (font (size 0.7 0.7) (thickness 0.15)) (justify left bottom mirror))
    )
    (fp_rect (start -0.93 0.47) (end 0.93 -0.47)
      (stroke (width 0.05) (type solid)) (fill none) (layer "B.CrtYd"))
    (fp_rect (start -0.5 0.25) (end 0.5 -0.25)
      (stroke (width 0.15) (type solid)) (fill none) (layer "B.Fab"))
    (pad "1" smd roundrect (at -0.485 0 180) (size 0.59 0.64) (layers "B.Cu" "B.Paste" "B.Mask") (roundrect_rratio 0.25)
      (net 17 "PS_1V8") (pintype "passive"))
    (pad "2" smd roundrect (at 0.485 0 180) (size 0.59 0.64) (layers "B.Cu" "B.Paste" "B.Mask") (roundrect_rratio 0.25)
      (net 30 "/Ethernet/MIO71") (pintype "passive"))
  )
	(footprint "kria-k26-devboard-footprints:C_0402_1005Metric" (layer "B.Cu")
    (at 149.245911 91.614035 90)
    (descr "Capacitor SMD 0402")
    (tags "capacitor SMD 0402")
    (property "Author" "Antmicro")
    (property "Dielectric" "")
    (property "License" "Apache-2.0")
    (property "MPN" "C1005X6S1A105K050BC")
    (property "Manufacturer" "TDK")
    (property "Sheetfile" "eth.kicad_sch")
    (property "Sheetname" "Ethernet")
    (property "Val" "1u")
    (property "Voltage" "")
    (property "ki_description" " ")
    (attr smd)
    (fp_text reference "C111" (at -0.895965 0.42 270) (layer "B.SilkS")
        (effects (font (size 0.7 0.7) (thickness 0.15)) (justify left bottom mirror))
    )
    (fp_text value "C_1u_0402" (at 0 -1.4 270) (layer "B.Fab") hide
        (effects (font (size 0.7 0.7) (thickness 0.15)) (justify left bottom mirror))
    )
    (fp_text user "${REFERENCE}" (at -0.932 -3.168 270) (layer "B.Fab") hide
        (effects (font (size 0.7 0.7) (thickness 0.15)) (justify left bottom mirror))
    )
    (fp_text user "License: Apache-2.0" (at -0.932 -5.17 270) (layer "B.Fab") hide
        (effects (font (size 0.7 0.7) (thickness 0.15)) (justify left bottom mirror))
    )
    (fp_text user "Author: Antmicro" (at -0.932 -4.17 270) (layer "B.Fab") hide
        (effects (font (size 0.7 0.7) (thickness 0.15)) (justify left bottom mirror))
    )
    (fp_rect (start -0.94 0.47) (end 0.94 -0.47)
      (stroke (width 0.05) (type solid)) (fill none) (layer "B.CrtYd"))
    (fp_rect (start -0.499 0.249) (end 0.499 -0.249)
      (stroke (width 0.15) (type solid)) (fill none) (layer "B.Fab"))
    (pad "1" smd roundrect (at -0.484 0 90) (size 0.59 0.64) (layers "B.Cu" "B.Paste" "B.Mask") (roundrect_rratio 0.25)
      (net 19 "PS_1V0") (pintype "passive"))
    (pad "2" smd roundrect (at 0.484 0 90) (size 0.59 0.64) (layers "B.Cu" "B.Paste" "B.Mask") (roundrect_rratio 0.25)
      (net 1 "GND") (pintype "passive"))
  )
	(footprint "kria-k26-devboard-footprints:C_0402_1005Metric" (layer "B.Cu")
    (at 148.45 85.762385 -90)
    (descr "Capacitor SMD 0402")
    (tags "capacitor SMD 0402")
    (property "Author" "Antmicro")
    (property "Dielectric" "")
    (property "License" "Apache-2.0")
    (property "MPN" "C1005X6S1A105K050BC")
    (property "Manufacturer" "TDK")
    (property "Sheetfile" "eth.kicad_sch")
    (property "Sheetname" "Ethernet")
    (property "Val" "1u")
    (property "Voltage" "")
    (property "ki_description" " ")
    (attr smd)
    (fp_text reference "C109" (at -3.712385 -0.37 90) (layer "B.SilkS")
        (effects (font (size 0.7 0.7) (thickness 0.15)) (justify left bottom mirror))
    )
    (fp_text value "C_1u_0402" (at 0 -1.4 90) (layer "B.Fab") hide
        (effects (font (size 0.7 0.7) (thickness 0.15)) (justify left bottom mirror))
    )
    (fp_text user "${REFERENCE}" (at -0.932 -3.168 90) (layer "B.Fab") hide
        (effects (font (size 0.7 0.7) (thickness 0.15)) (justify left bottom mirror))
    )
    (fp_text user "Author: Antmicro" (at -0.932 -4.17 90) (layer "B.Fab") hide
        (effects (font (size 0.7 0.7) (thickness 0.15)) (justify left bottom mirror))
    )
    (fp_text user "License: Apache-2.0" (at -0.932 -5.17 90) (layer "B.Fab") hide
        (effects (font (size 0.7 0.7) (thickness 0.15)) (justify left bottom mirror))
    )
    (fp_rect (start -0.94 0.47) (end 0.94 -0.47)
      (stroke (width 0.05) (type solid)) (fill none) (layer "B.CrtYd"))
    (fp_rect (start -0.499 0.249) (end 0.499 -0.249)
      (stroke (width 0.15) (type solid)) (fill none) (layer "B.Fab"))
    (pad "1" smd roundrect (at -0.484 0 270) (size 0.59 0.64) (layers "B.Cu" "B.Paste" "B.Mask") (roundrect_rratio 0.25)
      (net 19 "PS_1V0") (pintype "passive"))
    (pad "2" smd roundrect (at 0.484 0 270) (size 0.59 0.64) (layers "B.Cu" "B.Paste" "B.Mask") (roundrect_rratio 0.25)
      (net 1 "GND") (pintype "passive"))
  )
	(footprint "kria-k26-devboard-footprints:C_0603_1608Metric" (layer "B.Cu")
    (at 145.26 80.470911 90)
    (descr "Capacitor SMD 0603")
    (tags "capacitor 0603")
    (property "Author" "Antmicro")
    (property "License" "Apache-2.0")
    (property "MPN" "GRM188R61A106KE69D")
    (property "Manufacturer" "Murata")
    (property "Sheetfile" "eth.kicad_sch")
    (property "Sheetname" "Ethernet")
    (property "Val" "10u")
    (property "Voltage" "")
    (property "ki_description" " ")
    (attr smd)
    (fp_text reference "C91" (at 0.870911 2.36 270) (layer "B.SilkS")
        (effects (font (size 0.7 0.7) (thickness 0.15)) (justify left bottom mirror))
    )
    (fp_text value "C_10u_0603" (at 0 -1.6 270) (layer "B.Fab") hide
        (effects (font (size 0.7 0.7) (thickness 0.15)) (justify left bottom mirror))
    )
    (fp_text user "License: Apache-2.0" (at -1.682 -5.895 270) (layer "B.Fab") hide
        (effects (font (size 0.7 0.7) (thickness 0.15)) (justify left bottom mirror))
    )
    (fp_text user "${REFERENCE}" (at -1.682 -3.895 270) (layer "B.Fab") hide
        (effects (font (size 0.7 0.7) (thickness 0.15)) (justify left bottom mirror))
    )
    (fp_text user "Author: Antmicro" (at -1.682 -4.894 270) (layer "B.Fab") hide
        (effects (font (size 0.7 0.7) (thickness 0.15)) (justify left bottom mirror))
    )
    (fp_line (start -0.3 -0.3) (end 0.3 -0.3)
      (stroke (width 0.15) (type solid)) (layer "B.SilkS"))
    (fp_line (start -0.3 0.3) (end 0.3 0.3)
      (stroke (width 0.15) (type solid)) (layer "B.SilkS"))
    (fp_rect (start -1.24 0.7) (end 1.24 -0.7)
      (stroke (width 0.05) (type solid)) (fill none) (layer "B.CrtYd"))
    (fp_rect (start -0.8 0.4) (end 0.8 -0.4)
      (stroke (width 0.15) (type solid)) (fill none) (layer "B.Fab"))
    (pad "1" smd roundrect (at -0.7 0 90) (size 0.6 0.8) (layers "B.Cu" "B.Paste" "B.Mask") (roundrect_rratio 0.2)
      (net 16 "PS_2V5") (pintype "passive"))
    (pad "2" smd roundrect (at 0.7 0 90) (size 0.6 0.8) (layers "B.Cu" "B.Paste" "B.Mask") (roundrect_rratio 0.2)
      (net 1 "GND") (pintype "passive"))
  )
)
